# S9S_MB_2U (Grand Teton) — schematic parts with pin connectivity, parts 3121–3140 of 6093; source: Cadence DE-HDL packaged netlist (pstxprt.dat, pstxnet.dat, pstchip.dat)

PU51_P1_2  ISL99390FRZTR5935  ISL99390FRZ-TR5935 IC  pkg QFN21_6X5XB  page 293
  1  VOS  IN  = PVCCINFAON_CPU1_VOS2
  2  AGND  POWER  = GND
  3  VCC  POWER  = PVCCINFAON_CPU1_VDD2
  4  PVCC  POWER  = PVCCFA_EHV_CPU1_PVCC
  5  PGND1  POWER  = GND
  6  GL1  OUT  = NC
  7_9-20_24  PGND2  POWER  = GND
  10_19  SW  OUT  = SW_PVCCINFAON_CPU1_SW2
  25_29  VIN1  IN  = SW_P12V_PVCCINFAON_CPU1_FLT
  30  VIN2  IN  = SW_P12V_PVCCINFAON_CPU1_FLT
  31  DNC  TRI  = NC
  32  PHASE  POWER  = SW_PVCCINFAON_CPU1_BOOTR2
  33  BOOT  POWER  = SW_PVCCINFAON_CPU1_BOOT2
  34  PWM  IN  = PVCCINFAON_CPU1_APWM2
  35  EN  IN  = PVCCINFAON_CPU1_VDD2
  36  TOUT_FLT  OUT  = PVCCINFAON_CPU1_ATSEN
  37  LSET  OUT  = PVCCINFAON_CPU1_LSET2
  38  IOUT  OUT  = PVCCINFAON_CPU1_ACSP2
  39  REFIN  IN  = PVCCINFAON_CPU1_VREF
  40  PGND3  POWER  = GND
  41  GL2  OUT  = NC

PU69_P0_1  ISL99390FRZTR5935  ISL99390FRZ-TR5935 IC  pkg QFN21_6X5XB  page 271
  1  VOS  IN  = PVCCFA_EHV_FIVRA_CPU0_VOS1
  2  AGND  POWER  = GND
  3  VCC  POWER  = PVCCFA_EHV_FIVRA_CPU0_VDD1
  4  PVCC  POWER  = PVCCFA_EHV_FIVRA_CPU0_PVCC1
  5  PGND1  POWER  = GND
  6  GL1  OUT  = NC
  7_9-20_24  PGND2  POWER  = GND
  10_19  SW  OUT  = SW_PVCCFA_EHV_FIVRA_CPU0_SW1
  25_29  VIN1  IN  = SW_P12V_PVCCFA_EHV_FIVRA_CPU0_R
  30  VIN2  IN  = SW_P12V_PVCCFA_EHV_FIVRA_CPU0_R
  31  DNC  TRI  = NC
  32  PHASE  POWER  = SW_PVCCFA_EHV_FIVRA_CPU0_BOOTR1
  33  BOOT  POWER  = SW_PVCCFA_EHV_FIVRA_CPU0_BOOT1
  34  PWM  IN  = PVCCFA_EHV_FIVRA_CPU0_PWM1
  35  EN  IN  = PVCCFA_EHV_FIVRA_CPU0_VDD1
  36  TOUT_FLT  OUT  = PVCCFA_EHV_FIVRA_CPU0_BTSEN
  37  LSET  OUT  = PVCCFA_EHV_FIVRA_CPU0_LSET1
  38  IOUT  OUT  = PVCCFA_EHV_FIVRA_CPU0_IMON1
  39  REFIN  IN  = PVCCIN_CPU0_VREF
  40  PGND3  POWER  = GND
  41  GL2  OUT  = NC

PU70_P0_2  ISL99390FRZTR5935  ISL99390FRZ-TR5935 IC  pkg QFN21_6X5XB  page 271
  1  VOS  IN  = PVCCFA_EHV_FIVRA_CPU0_VOS2
  2  AGND  POWER  = GND
  3  VCC  POWER  = PVCCFA_EHV_FIVRA_CPU0_VDD2
  4  PVCC  POWER  = PVCCFA_EHV_FIVRA_CPU0_PVCC2
  5  PGND1  POWER  = GND
  6  GL1  OUT  = NC
  7_9-20_24  PGND2  POWER  = GND
  10_19  SW  OUT  = SW_PVCCFA_EHV_FIVRA_CPU0_SW2
  25_29  VIN1  IN  = SW_P12V_PVCCFA_EHV_FIVRA_CPU0_L
  30  VIN2  IN  = SW_P12V_PVCCFA_EHV_FIVRA_CPU0_L
  31  DNC  TRI  = NC
  32  PHASE  POWER  = SW_PVCCFA_EHV_FIVRA_CPU0_BOOTR2
  33  BOOT  POWER  = SW_PVCCFA_EHV_FIVRA_CPU0_BOOT2
  34  PWM  IN  = PVCCFA_EHV_FIVRA_CPU0_PWM2
  35  EN  IN  = PVCCFA_EHV_FIVRA_CPU0_VDD2
  36  TOUT_FLT  OUT  = PVCCFA_EHV_FIVRA_CPU0_BTSEN
  37  LSET  OUT  = PVCCFA_EHV_FIVRA_CPU0_LSET2
  38  IOUT  OUT  = PVCCFA_EHV_FIVRA_CPU0_IMON2
  39  REFIN  IN  = PVCCIN_CPU0_VREF
  40  PGND3  POWER  = GND
  41  GL2  OUT  = NC

PU71_P0_3  ISL99390FRZTR5935  ISL99390FRZ-TR5935 IC  pkg QFN21_6X5XB  page 272
  1  VOS  IN  = PVCCFA_EHV_FIVRA_CPU0_VOS3
  2  AGND  POWER  = GND
  3  VCC  POWER  = PVCCFA_EHV_FIVRA_CPU0_VDD3
  4  PVCC  POWER  = PVCCFA_EHV_FIVRA_CPU0_PVCC1
  5  PGND1  POWER  = GND
  6  GL1  OUT  = NC
  7_9-20_24  PGND2  POWER  = GND
  10_19  SW  OUT  = SW_PVCCFA_EHV_FIVRA_CPU0_SW3
  25_29  VIN1  IN  = SW_P12V_PVCCFA_EHV_FIVRA_CPU0_R
  30  VIN2  IN  = SW_P12V_PVCCFA_EHV_FIVRA_CPU0_R
  31  DNC  TRI  = NC
  32  PHASE  POWER  = SW_PVCCFA_EHV_FIVRA_CPU0_BOOTR3
  33  BOOT  POWER  = SW_PVCCFA_EHV_FIVRA_CPU0_BOOT3
  34  PWM  IN  = PVCCFA_EHV_FIVRA_CPU0_PWM3
  35  EN  IN  = PVCCFA_EHV_FIVRA_CPU0_VDD3
  36  TOUT_FLT  OUT  = PVCCFA_EHV_FIVRA_CPU0_BTSEN
  37  LSET  OUT  = PVCCFA_EHV_FIVRA_CPU0_LSET3
  38  IOUT  OUT  = PVCCFA_EHV_FIVRA_CPU0_IMON3
  39  REFIN  IN  = PVCCIN_CPU0_VREF
  40  PGND3  POWER  = GND
  41  GL2  OUT  = NC

PU72_P0_4  ISL99390FRZTR5935  ISL99390FRZ-TR5935 IC  pkg QFN21_6X5XB  page 272
  1  VOS  IN  = PVCCFA_EHV_FIVRA_CPU0_VOS4
  2  AGND  POWER  = GND
  3  VCC  POWER  = PVCCFA_EHV_FIVRA_CPU0_VDD4
  4  PVCC  POWER  = PVCCFA_EHV_FIVRA_CPU0_PVCC2
  5  PGND1  POWER  = GND
  6  GL1  OUT  = NC
  7_9-20_24  PGND2  POWER  = GND
  10_19  SW  OUT  = SW_PVCCFA_EHV_FIVRA_CPU0_SW4
  25_29  VIN1  IN  = SW_P12V_PVCCFA_EHV_FIVRA_CPU0_L
  30  VIN2  IN  = SW_P12V_PVCCFA_EHV_FIVRA_CPU0_L
  31  DNC  TRI  = NC
  32  PHASE  POWER  = SW_PVCCFA_EHV_FIVRA_CPU0_BOOTR4
  33  BOOT  POWER  = SW_PVCCFA_EHV_FIVRA_CPU0_BOOT4
  34  PWM  IN  = PVCCFA_EHV_FIVRA_CPU0_PWM4
  35  EN  IN  = PVCCFA_EHV_FIVRA_CPU0_VDD4
  36  TOUT_FLT  OUT  = PVCCFA_EHV_FIVRA_CPU0_BTSEN
  37  LSET  OUT  = PVCCFA_EHV_FIVRA_CPU0_LSET4
  38  IOUT  OUT  = PVCCFA_EHV_FIVRA_CPU0_IMON4
  39  REFIN  IN  = PVCCIN_CPU0_VREF
  40  PGND3  POWER  = GND
  41  GL2  OUT  = NC

PU73  RS53319LR  IC  pkg QFN21_4X3  page 262
  1  BST  IN  = SW_P1V05_PCH_AUX_BST
  2  AGND  POWER  = GND
  3  CS  IN  = P1V05_PCH_AUX_CS
  4  MODE  IN  = P1V05_PCH_AUX_MODE
  5  REF  IN  = P1V05_PCH_AUX_REF
  6  RTN  POWER  = SH_P1V05_PCH_AUX_N
  7  FB  IN  = P1V05_PCH_AUX_FB
  8  EN  IN  = FM_P1V05_PCH_AUX_R_EN
  9  PGOOD  OUT  = PWRGD_P1V05_PCH_AUX_R
  10  VIN1  POWER  = SW_P12V_AUX_P1V05_PCH_AUX_FLT
  11_18  PGND  POWER  = GND
  19  VCC  POWER  = P1V05_PCH_AUX_VCC
  20  SW  OUT  = SW_P1V05_PCH_AUX_SW
  21  VIN2  POWER  = SW_P12V_AUX_P1V05_PCH_AUX_FLT

PU74  NB682GDZ  NB682GD-Z IC  pkg QFN13_2X3  page 263
  1  VIN  POWER  = SW_P1V8_PCH_AUX_FLT
  2  PGND  POWER  = GND
  3  C1  IN  = P1V8_PCH_AUX_VCC
  4  C0  IN  = GND
  5  EN  IN  = FM_PCH_P1V8_AUX_EN_R
  6  \lp#\  IN  = P1V8_PCH_AUX_VCC
  7  MODE  IN  = P1V8_PCH_AUX_MODE
  8  SW  POWER  = SW_P1V8_PCH_AUX_SW
  9  BST  POWER  = SW_P1V8_PCH_AUX_BST
  10  \3v3\  POWER  = P1V8_PCH_AUX_VCC
  11  AGND  POWER  = GND
  12  VOUT  POWER  = P1V8_PCH_AUX
  13  PG  OUT  = PWRGD_P1V8_PCH_AUX_R

PU75_P1_1  ISL99390FRZTR5935  ISL99390FRZ-TR5935 IC  pkg QFN21_6X5XB  page 289
  1  VOS  IN  = PVCCFA_EHV_FIVRA_CPU1_VOS1
  2  AGND  POWER  = GND
  3  VCC  POWER  = PVCCFA_EHV_FIVRA_CPU1_VDD1
  4  PVCC  POWER  = PVCCFA_EHV_FIVRA_CPU1_PVCC1
  5  PGND1  POWER  = GND
  6  GL1  OUT  = NC
  7_9-20_24  PGND2  POWER  = GND
  10_19  SW  OUT  = SW_PVCCFA_EHV_FIVRA_CPU1_SW1
  25_29  VIN1  IN  = SW_P12V_PVCCFA_EHV_FIVRA_CPU1_R
  30  VIN2  IN  = SW_P12V_PVCCFA_EHV_FIVRA_CPU1_R
  31  DNC  TRI  = NC
  32  PHASE  POWER  = SW_PVCCFA_EHV_FIVRA_CPU1_BOOTR1
  33  BOOT  POWER  = SW_PVCCFA_EHV_FIVRA_CPU1_BOOT1
  34  PWM  IN  = PVCCFA_EHV_FIVRA_CPU1_PWM1
  35  EN  IN  = PVCCFA_EHV_FIVRA_CPU1_VDD1
  36  TOUT_FLT  OUT  = PVCCFA_EHV_FIVRA_CPU1_BTSEN
  37  LSET  OUT  = PVCCFA_EHV_FIVRA_CPU1_LSET1
  38  IOUT  OUT  = PVCCFA_EHV_FIVRA_CPU1_IMON1
  39  REFIN  IN  = PVCCIN_CPU1_VREF
  40  PGND3  POWER  = GND
  41  GL2  OUT  = NC

PU76_P1_2  ISL99390FRZTR5935  ISL99390FRZ-TR5935 IC  pkg QFN21_6X5XB  page 289
  1  VOS  IN  = PVCCFA_EHV_FIVRA_CPU1_VOS2
  2  AGND  POWER  = GND
  3  VCC  POWER  = PVCCFA_EHV_FIVRA_CPU1_VDD2
  4  PVCC  POWER  = PVCCFA_EHV_FIVRA_CPU1_PVCC2
  5  PGND1  POWER  = GND
  6  GL1  OUT  = NC
  7_9-20_24  PGND2  POWER  = GND
  10_19  SW  OUT  = SW_PVCCFA_EHV_FIVRA_CPU1_SW2
  25_29  VIN1  IN  = SW_P12V_PVCCFA_EHV_FIVRA_CPU1_L
  30  VIN2  IN  = SW_P12V_PVCCFA_EHV_FIVRA_CPU1_L
  31  DNC  TRI  = NC
  32  PHASE  POWER  = SW_PVCCFA_EHV_FIVRA_CPU1_BOOTR2
  33  BOOT  POWER  = SW_PVCCFA_EHV_FIVRA_CPU1_BOOT2
  34  PWM  IN  = PVCCFA_EHV_FIVRA_CPU1_PWM2
  35  EN  IN  = PVCCFA_EHV_FIVRA_CPU1_VDD2
  36  TOUT_FLT  OUT  = PVCCFA_EHV_FIVRA_CPU1_BTSEN
  37  LSET  OUT  = PVCCFA_EHV_FIVRA_CPU1_LSET2
  38  IOUT  OUT  = PVCCFA_EHV_FIVRA_CPU1_IMON2
  39  REFIN  IN  = PVCCIN_CPU1_VREF
  40  PGND3  POWER  = GND
  41  GL2  OUT  = NC

PU77_P1_3  ISL99390FRZTR5935  ISL99390FRZ-TR5935 IC  pkg QFN21_6X5XB  page 290
  1  VOS  IN  = PVCCFA_EHV_FIVRA_CPU1_VOS3
  2  AGND  POWER  = GND
  3  VCC  POWER  = PVCCFA_EHV_FIVRA_CPU1_VDD3
  4  PVCC  POWER  = PVCCFA_EHV_FIVRA_CPU1_PVCC1
  5  PGND1  POWER  = GND
  6  GL1  OUT  = NC
  7_9-20_24  PGND2  POWER  = GND
  10_19  SW  OUT  = SW_PVCCFA_EHV_FIVRA_CPU1_SW3
  25_29  VIN1  IN  = SW_P12V_PVCCFA_EHV_FIVRA_CPU1_R
  30  VIN2  IN  = SW_P12V_PVCCFA_EHV_FIVRA_CPU1_R
  31  DNC  TRI  = NC
  32  PHASE  POWER  = SW_PVCCFA_EHV_FIVRA_CPU1_BOOTR3
  33  BOOT  POWER  = SW_PVCCFA_EHV_FIVRA_CPU1_BOOT3
  34  PWM  IN  = PVCCFA_EHV_FIVRA_CPU1_PWM3
  35  EN  IN  = PVCCFA_EHV_FIVRA_CPU1_VDD3
  36  TOUT_FLT  OUT  = PVCCFA_EHV_FIVRA_CPU1_BTSEN
  37  LSET  OUT  = PVCCFA_EHV_FIVRA_CPU1_LSET3
  38  IOUT  OUT  = PVCCFA_EHV_FIVRA_CPU1_IMON3
  39  REFIN  IN  = PVCCIN_CPU1_VREF
  40  PGND3  POWER  = GND
  41  GL2  OUT  = NC

PU78_P1_4  ISL99390FRZTR5935  ISL99390FRZ-TR5935 IC  pkg QFN21_6X5XB  page 290
  1  VOS  IN  = PVCCFA_EHV_FIVRA_CPU1_VOS4
  2  AGND  POWER  = GND
  3  VCC  POWER  = PVCCFA_EHV_FIVRA_CPU1_VDD4
  4  PVCC  POWER  = PVCCFA_EHV_FIVRA_CPU1_PVCC2
  5  PGND1  POWER  = GND
  6  GL1  OUT  = NC
  7_9-20_24  PGND2  POWER  = GND
  10_19  SW  OUT  = SW_PVCCFA_EHV_FIVRA_CPU1_SW4
  25_29  VIN1  IN  = SW_P12V_PVCCFA_EHV_FIVRA_CPU1_L
  30  VIN2  IN  = SW_P12V_PVCCFA_EHV_FIVRA_CPU1_L
  31  DNC  TRI  = NC
  32  PHASE  POWER  = SW_PVCCFA_EHV_FIVRA_CPU1_BOOTR4
  33  BOOT  POWER  = SW_PVCCFA_EHV_FIVRA_CPU1_BOOT4
  34  PWM  IN  = PVCCFA_EHV_FIVRA_CPU1_PWM4
  35  EN  IN  = PVCCFA_EHV_FIVRA_CPU1_VDD4
  36  TOUT_FLT  OUT  = PVCCFA_EHV_FIVRA_CPU1_BTSEN
  37  LSET  OUT  = PVCCFA_EHV_FIVRA_CPU1_LSET4
  38  IOUT  OUT  = PVCCFA_EHV_FIVRA_CPU1_IMON4
  39  REFIN  IN  = PVCCIN_CPU1_VREF
  40  PGND3  POWER  = GND
  41  GL2  OUT  = NC

PU79  RS53318LR  IC  pkg QFN21_4X3  page 281
  1  BST  IN  = SW_PVPP_HBM_CPU0_BST
  2  AGND  POWER  = GND
  3  CS  IN  = PVPP_HBM_CPU0_CS
  4  MODE  IN  = PVPP_HBM_CPU0_MODE
  5  REF  IN  = PVPP_HBM_CPU0_REF
  6  RTN  POWER  = SH_PVPP_HBM_CPU0_N
  7  FB  IN  = PVPP_HBM_CPU0_FB
  8  EN  IN  = FM_PVPP_HBM_CPU0_EN
  9  PGOOD  OUT  = PWRGD_PVPP_HBM_CPU0_R
  10  VIN1  POWER  = SW_P12V_PVCCIN_CPU0_FLT
  11_18  PGND  POWER  = GND
  19  VCC  POWER  = PVPP_HBM_CPU0_VCC
  20  SW  OUT  = SW_PVPP_HBM_CPU0_SW
  21  VIN2  POWER  = SW_P12V_PVCCIN_CPU0_FLT

PU80  RS53318LR  IC  pkg QFN21_4X3  page 299
  1  BST  IN  = SW_PVPP_HBM_CPU1_BST
  2  AGND  POWER  = GND
  3  CS  IN  = PVPP_HBM_CPU1_CS
  4  MODE  IN  = PVPP_HBM_CPU1_MODE
  5  REF  IN  = PVPP_HBM_CPU1_REF
  6  RTN  POWER  = SH_PVPP_HBM_CPU1_N
  7  FB  IN  = PVPP_HBM_CPU1_FB
  8  EN  IN  = FM_PVPP_HBM_CPU1_EN
  9  PGOOD  OUT  = PWRGD_PVPP_HBM_CPU1_R
  10  VIN1  POWER  = SW_P12V_PVCCIN_CPU1_FLT
  11_18  PGND  POWER  = GND
  19  VCC  POWER  = PVPP_HBM_CPU1_VCC
  20  SW  OUT  = SW_PVPP_HBM_CPU1_SW
  21  VIN2  POWER  = SW_P12V_PVCCIN_CPU1_FLT

PU81  RS53317LR  IC  pkg QFN14_0-5_3X2XB  page 282
  1  PGND1  POWER  = GND
  2  SW1  OUT  = SW_PVNN_MAIN_CPU0_SW
  3  VIN  IN  = SW_P12V_PVCCINFAON_CPU0_FLT
  4  CS  BI  = PVNN_MAIN_CPU0_CS
  5  EN  IN  = FM_PVNN_MAIN_CPU0_EN
  6  FB  IN  = PVNN_MAIN_CPU0_FB
  7  AGND  POWER  = GND
  8  REF  BI  = PVNN_MAIN_CPU0_REF
  9  PGOOD  OUT  = PWRGD_PVNN_MAIN_CPU0_R
  10  BST  BI  = SW_PVNN_MAIN_CPU0_BST
  11  SW2  OUT  = SW_PVNN_MAIN_CPU0_SW
  12  MODE  IN  = PVNN_MAIN_CPU0_MODE
  13  VCC  POWER  = PVNN_MAIN_CPU0_VCC
  14  PGND2  POWER  = GND

PU82  RS53317LR  IC  pkg QFN14_0-5_3X2XB  page 300
  1  PGND1  POWER  = GND
  2  SW1  OUT  = SW_PVNN_MAIN_CPU1_SW
  3  VIN  IN  = SW_P12V_PVCCINFAON_CPU1_FLT
  4  CS  BI  = PVNN_MAIN_CPU1_CS
  5  EN  IN  = FM_PVNN_MAIN_CPU1_EN
  6  FB  IN  = PVNN_MAIN_CPU1_FB
  7  AGND  POWER  = GND
  8  REF  BI  = PVNN_MAIN_CPU1_REF
  9  PGOOD  OUT  = PWRGD_PVNN_MAIN_CPU1_R
  10  BST  BI  = SW_PVNN_MAIN_CPU1_BST
  11  SW2  OUT  = SW_PVNN_MAIN_CPU1_SW
  12  MODE  IN  = PVNN_MAIN_CPU1_MODE
  13  VCC  POWER  = PVNN_MAIN_CPU1_VCC
  14  PGND2  POWER  = GND

PU173  MOSFET_N  BSS138K EMPTY  pkg SMLF  page 281
  D  DRAIN  OUT  = FM_HBM_VPP_SEL_CPU0_D
  G  GATE  IN  = FM_HBM2_HBM3_VPP_SEL
  S  SOURCE  BI  = SH_PVPP_HBM_CPU0_N

PU174  MOSFET_N  BSS138K EMPTY  pkg SMLF  page 299
  D  DRAIN  OUT  = FM_HBM_VPP_SEL_CPU1_D
  G  GATE  IN  = FM_HBM2_HBM3_VPP_SEL
  S  SOURCE  BI  = SH_PVPP_HBM_CPU1_N

PU181  RS53318LR  IC  pkg QFN21_4X3  page 258
  1  BST  IN  = SW_P5V_AUX_BST
  2  AGND  POWER  = GND
  3  CS  IN  = P5V_AUX_CS
  4  MODE  IN  = P5V_AUX_MODE
  5  REF  IN  = P5V_AUX_REF
  6  RTN  POWER  = GND
  7  FB  IN  = P5V_AUX_FB
  8  EN  IN  = PWRGD_P3V3_AUX
  9  PGOOD  OUT  = PWRGD_P5V_AUX_R
  10  VIN1  POWER  = SW_P5V_AUX_FLT
  11_18  PGND  POWER  = GND
  19  VCC  POWER  = P5V_AUX_VCC
  20  SW  OUT  = SW_P5V_AUX_SW
  21  VIN2  POWER  = SW_P5V_AUX_FLT

PU200  MAX15090BEWIT  MAX15090BEWI+T IC  pkg BGA28_0-5_3-525X2-065  page 162
  A1  ISENSE  OUT  = P3V3_OCP_SENSE_2
  A2  VCC  POWER  = P3V3_OCP_VCC_2
  A3  IN_A3  IN  = P3V3_AUX
  A4  OUT_A4  OUT  = P3V3_OCP_V3_2_R
  A5  IN_A5  IN  = P3V3_AUX
  A6  GATE  BI  = P3V3_OCP_GATE_2
  A7  CDLY  IN  = GND
  B1  CB  BI  = P3V3_OCP_CB_2
  B2  GND_B2  POWER  = GND
  B3  IN_B3  IN  = P3V3_AUX
  B4  OUT_B4  OUT  = P3V3_OCP_V3_2_R
  B5  IN_B5  IN  = P3V3_AUX
  B6  OUT_B6  OUT  = P3V3_OCP_V3_2_R
  B7  \en#\  IN  = GND
  C1  GND_C1  POWER  = GND
  C2  GND_C2  POWER  = GND
  C3  IN_C3  IN  = P3V3_AUX
  C4  OUT_C4  OUT  = P3V3_OCP_V3_2_R
  C5  IN_C5  IN  = P3V3_AUX
  C6  OUT_C6  OUT  = P3V3_OCP_V3_2_R
  C7  \fault#\  OUT  = P3V3_OCP_FAULT_2
  D1  REG  OUT  = P3V3_OCP_REG_2
  D2  UV  IN  = P3V3_OCP_UV_2
  D3  OV  IN  = P3V3_OCP_OV_2
  D4  OUT_D4  OUT  = P3V3_OCP_V3_2_R
  D5  IN_D5  IN  = P3V3_AUX
  D6  OUT_D6  OUT  = P3V3_OCP_V3_2_R
  D7  PG  OUT  = P3V3_OCP_PWRGD_2

PU201  MAX15090BEWIT  MAX15090BEWI+T EMPTY  pkg BGA28_0-5_3-525X2-065  page 162
  A1  ISENSE  OUT  = P12V_OCP_SENSE_2
  A2  VCC  POWER  = P12V_OCP_VCC_2
  A3  IN_A3  IN  = P12V_AUX
  A4  OUT_A4  OUT  = P12V_OCP_V3_2
  A5  IN_A5  IN  = P12V_AUX
  A6  GATE  BI  = P12V_OCP_GATE_2
  A7  CDLY  IN  = GND
  B1  CB  BI  = P12V_OCP_CB_2
  B2  GND_B2  POWER  = GND
  B3  IN_B3  IN  = P12V_AUX
  B4  OUT_B4  OUT  = P12V_OCP_V3_2
  B5  IN_B5  IN  = P12V_AUX
  B6  OUT_B6  OUT  = P12V_OCP_V3_2
  B7  \en#\  IN  = GND
  C1  GND_C1  POWER  = GND
  C2  GND_C2  POWER  = GND
  C3  IN_C3  IN  = P12V_AUX
  C4  OUT_C4  OUT  = P12V_OCP_V3_2
  C5  IN_C5  IN  = P12V_AUX
  C6  OUT_C6  OUT  = P12V_OCP_V3_2
  C7  \fault#\  OUT  = P12V_OCP_FAULT_2
  D1  REG  OUT  = P12V_OCP_REG_2
  D2  UV  IN  = P12V_OCP_UV_2
  D3  OV  IN  = P12V_OCP_OV_2
  D4  OUT_D4  OUT  = P12V_OCP_V3_2
  D5  IN_D5  IN  = P12V_AUX
  D6  OUT_D6  OUT  = P12V_OCP_V3_2
  D7  PG  OUT  = P12V_OCP_PWRGD_2
